# T6G (Grand Teton) — schematic netlist excerpt (pin names and nets, part order shuffled) for the footprints in the layout excerpt that follows; sources: Cadence DE-HDL packaged netlist, KiCad conversion of 04192023_DAF0TMB3IC0_F0TG_MB_C_brd_V02_OCP.brd

PL6002  Q_INDUCTOR  BLM18SN220TN1D/8000MA IND  pkg SMLF  page 269 : \1\ = P12V_AUX ; \2\ = SW_P12V_AUX_P1V8_AUX_FLT
R4201  Q_RES  1K 1% CHIP  pkg 0402LF  page 235 : A = U273_3_ADD0 ; B = GND

(kicad_pcb
	(version 20260206)
	(generator "pcbnew")
	(generator_version "10.0")
	(general
		(thickness 1.6)
		(legacy_teardrops no)
	)
	(paper "A4")
	(title_block
		(title "04192023_DAF0TMB3IC0_F0TG_MB_C_brd_V02_OCP.brd")
		(comment 1 "Grand Teton / footprints 2739-2740 of 8354")
	)
	(layers
		(0 "F.Cu" signal "TOP")
		(4 "In1.Cu" signal "GND")
		(6 "In2.Cu" signal "IN1")
		(8 "In3.Cu" signal "GND1")
		(10 "In4.Cu" signal "IN2")
		(12 "In5.Cu" signal "GND2")
		(14 "In6.Cu" signal "IN3")
		(16 "In7.Cu" signal "GND3")
		(18 "In8.Cu" signal "VCC")
		(20 "In9.Cu" signal "VCC1")
		(22 "In10.Cu" signal "GND4")
		(24 "In11.Cu" signal "IN4")
		(26 "In12.Cu" signal "GND5")
		(28 "In13.Cu" signal "IN5")
		(30 "In14.Cu" signal "GND6")
		(32 "In15.Cu" signal "IN6")
		(34 "In16.Cu" signal "GND7")
		(2 "B.Cu" signal "BOTTOM")
		(9 "F.Adhes" user "F.Adhesive")
		(11 "B.Adhes" user "B.Adhesive")
		(13 "F.Paste" user "Package Geometry/Pastemask Top")
		(15 "B.Paste" user "Package Geometry/Pastemask Bottom")
		(5 "F.SilkS" user "Ref Des/Silkscreen Top")
		(7 "B.SilkS" user "Ref Des/Silkscreen Bottom")
		(1 "F.Mask" user "Board Geometry/Soldermask Top")
		(3 "B.Mask" user "Board Geometry/Soldermask Bottom")
		(17 "Dwgs.User" user "User.Drawings")
		(19 "Cmts.User" user "User.Comments")
		(21 "Eco1.User" user "User.Eco1")
		(23 "Eco2.User" user "User.Eco2")
		(25 "Edge.Cuts" user "Board Geometry/Outline")
		(27 "Margin" user)
		(31 "F.CrtYd" user "Package Geometry/Place Bound Top")
		(29 "B.CrtYd" user "Package Geometry/Place Bound Bottom")
		(35 "F.Fab" user "Ref Des/Assembly Top")
		(33 "B.Fab" user "Ref Des/Assembly Bottom")
	)
	(footprint ""
		(layer "F.Cu")
		(at 137.974832 -76.242672 90)
		(property "Reference" "PL6002"
			(at 0 0 90)
			(layer "F.SilkS")
			(hide yes)
			(effects
				(font
					(size 1.27 1.27)
				)
			)
		)
		(property "Value" ""
			(at 0 0 90)
			(layer "F.Fab")
			(effects
				(font
					(size 1.27 1.27)
				)
			)
		)
		(duplicate_pad_numbers_are_jumpers no)
		(fp_line
			(start -1.27 -0.5842)
			(end 1.27 -0.5842)
			(stroke
				(width 0.1524)
				(type default)
			)
			(layer "F.SilkS")
		)
		(fp_line
			(start -1.27 -0.5588)
			(end -1.27 -0.5842)
			(stroke
				(width 0.1524)
				(type default)
			)
			(layer "F.SilkS")
		)
		(fp_line
			(start 1.27 0.5842)
			(end 1.27 -0.5842)
			(stroke
				(width 0.1524)
				(type default)
			)
			(layer "F.SilkS")
		)
		(fp_line
			(start 1.27 0.5842)
			(end -1.27 0.5842)
			(stroke
				(width 0.1524)
				(type default)
			)
			(layer "F.SilkS")
		)
		(fp_line
			(start -1.27 0.5842)
			(end -1.27 -0.5842)
			(stroke
				(width 0.1524)
				(type default)
			)
			(layer "F.SilkS")
		)
		(fp_line
			(start 0.9144 -0.508)
			(end 0.9144 -0.406654)
			(stroke
				(width 0.1)
				(type default)
			)
			(layer "F.Fab")
		)
		(fp_line
			(start -0.9144 -0.508)
			(end 0.9144 -0.508)
			(stroke
				(width 0.1)
				(type default)
			)
			(layer "F.Fab")
		)
		(fp_line
			(start 1.1938 -0.406654)
			(end 1.1938 0.4064)
			(stroke
				(width 0.1)
				(type default)
			)
			(layer "F.Fab")
		)
		(fp_line
			(start 0.9144 -0.406654)
			(end 1.1938 -0.406654)
			(stroke
				(width 0.1)
				(type default)
			)
			(layer "F.Fab")
		)
		(fp_line
			(start -0.9144 -0.406654)
			(end -0.9144 -0.508)
			(stroke
				(width 0.1)
				(type default)
			)
			(layer "F.Fab")
		)
		(fp_line
			(start -1.194308 -0.406654)
			(end -0.9144 -0.406654)
			(stroke
				(width 0.1)
				(type default)
			)
			(layer "F.Fab")
		)
		(fp_line
			(start 1.1938 0.4064)
			(end 0.9144 0.4064)
			(stroke
				(width 0.1)
				(type default)
			)
			(layer "F.Fab")
		)
		(fp_line
			(start 0.9144 0.4064)
			(end 0.9144 0.508)
			(stroke
				(width 0.1)
				(type default)
			)
			(layer "F.Fab")
		)
		(fp_line
			(start -0.9144 0.406654)
			(end -1.194308 0.406654)
			(stroke
				(width 0.1)
				(type default)
			)
			(layer "F.Fab")
		)
		(fp_line
			(start -1.194308 0.406654)
			(end -1.194308 -0.406654)
			(stroke
				(width 0.1)
				(type default)
			)
			(layer "F.Fab")
		)
		(fp_line
			(start 0.9144 0.508)
			(end -0.9144 0.508)
			(stroke
				(width 0.1)
				(type default)
			)
			(layer "F.Fab")
		)
		(fp_line
			(start -0.9144 0.508)
			(end -0.9144 0.406654)
			(stroke
				(width 0.1)
				(type default)
			)
			(layer "F.Fab")
		)
		(pad "1" smd rect
			(at -0.7366 0)
			(size 0.7112 0.8128)
			(layers "F.Cu" "F.Mask" "F.Paste")
			(net "P12V_AUX")
		)
		(pad "2" smd rect
			(at 0.7366 0)
			(size 0.7112 0.8128)
			(layers "F.Cu" "F.Mask" "F.Paste")
			(net "SW_P12V_AUX_P1V8_AUX_FLT")
		)
	)
	(footprint ""
		(layer "F.Cu")
		(at 120.358662 -16.50365)
		(property "Reference" "R4201"
			(at 0 0 0)
			(layer "F.SilkS")
			(hide yes)
			(effects
				(font
					(size 1.27 1.27)
				)
			)
		)
		(property "Value" ""
			(at 0 0 0)
			(layer "F.Fab")
			(effects
				(font
					(size 1.27 1.27)
				)
			)
		)
		(duplicate_pad_numbers_are_jumpers no)
		(fp_line
			(start -0.7874 -0.4064)
			(end 0.7874 -0.4064)
			(stroke
				(width 0.1524)
				(type default)
			)
			(layer "F.SilkS")
		)
		(fp_line
			(start -0.7874 0.4064)
			(end -0.7874 -0.4064)
			(stroke
				(width 0.1524)
				(type default)
			)
			(layer "F.SilkS")
		)
		(fp_line
			(start 0.7874 -0.4064)
			(end 0.7874 0.4064)
			(stroke
				(width 0.1524)
				(type default)
			)
			(layer "F.SilkS")
		)
		(fp_line
			(start 0.7874 0.4064)
			(end -0.7874 0.4064)
			(stroke
				(width 0.1524)
				(type default)
			)
			(layer "F.SilkS")
		)
		(fp_line
			(start -0.67945 -0.305054)
			(end -0.12065 -0.305054)
			(stroke
				(width 0.1)
				(type default)
			)
			(layer "F.Fab")
		)
		(fp_line
			(start -0.67945 0.3048)
			(end -0.67945 -0.305054)
			(stroke
				(width 0.1)
				(type default)
			)
			(layer "F.Fab")
		)
		(fp_line
			(start -0.12065 -0.305054)
			(end -0.12065 -0.2794)
			(stroke
				(width 0.1)
				(type default)
			)
			(layer "F.Fab")
		)
		(fp_line
			(start -0.12065 -0.2794)
			(end 0.12065 -0.2794)
			(stroke
				(width 0.1)
				(type default)
			)
			(layer "F.Fab")
		)
		(fp_line
			(start -0.12065 0.2794)
			(end -0.12065 0.3048)
			(stroke
				(width 0.1)
				(type default)
			)
			(layer "F.Fab")
		)
		(fp_line
			(start -0.12065 0.3048)
			(end -0.67945 0.3048)
			(stroke
				(width 0.1)
				(type default)
			)
			(layer "F.Fab")
		)
		(fp_line
			(start 0.120396 0.2794)
			(end -0.12065 0.2794)
			(stroke
				(width 0.1)
				(type default)
			)
			(layer "F.Fab")
		)
		(fp_line
			(start 0.120396 0.3048)
			(end 0.120396 0.2794)
			(stroke
				(width 0.1)
				(type default)
			)
			(layer "F.Fab")
		)
		(fp_line
			(start 0.12065 -0.3048)
			(end 0.67945 -0.3048)
			(stroke
				(width 0.1)
				(type default)
			)
			(layer "F.Fab")
		)
		(fp_line
			(start 0.12065 -0.2794)
			(end 0.12065 -0.3048)
			(stroke
				(width 0.1)
				(type default)
			)
			(layer "F.Fab")
		)
		(fp_line
			(start 0.67945 -0.3048)
			(end 0.67945 0.3048)
			(stroke
				(width 0.1)
				(type default)
			)
			(layer "F.Fab")
		)
		(fp_line
			(start 0.67945 0.3048)
			(end 0.120396 0.3048)
			(stroke
				(width 0.1)
				(type default)
			)
			(layer "F.Fab")
		)
		(pad "1" smd circle
			(at -0.40005 0)
			(size 0 0)
			(layers "F.Cu" "F.Mask" "F.Paste")
			(net "U273_3_ADD0")
		)
		(pad "2" smd circle
			(at 0.40005 0)
			(size 0 0)
			(layers "F.Cu" "F.Mask" "F.Paste")
			(net "GND")
		)
	)
)
